(kicad_pcb
	(version 20260206)
	(generator "pcbnew")
	(generator_version "10.0")
	(general
		(thickness 1.6)
		(legacy_teardrops no)
	)
	(paper "A4")
	(title_block
		(title "v1-chassis-manager — T6M_CM_d_v01_1031_1645.brd")
		(comment 1 "Open CloudServer (Microsoft) / footprints 229-237 of 2512")
	)
	(layers
		(0 "F.Cu" signal "TOP")
		(4 "In1.Cu" signal "GND1")
		(6 "In2.Cu" signal "IN1")
		(8 "In3.Cu" signal "VCC1")
		(10 "In4.Cu" signal "VCC2")
		(12 "In5.Cu" signal "GND2")
		(14 "In6.Cu" signal "IN2")
		(16 "In7.Cu" signal "IN3")
		(18 "In8.Cu" signal "GND3")
		(2 "B.Cu" signal "BOTTOM")
		(9 "F.Adhes" user "F.Adhesive")
		(11 "B.Adhes" user "B.Adhesive")
		(13 "F.Paste" user "Package Geometry/Pastemask Top")
		(15 "B.Paste" user "Package Geometry/Pastemask Bottom")
		(5 "F.SilkS" user "Ref Des/Silkscreen Top")
		(7 "B.SilkS" user "Ref Des/Silkscreen Bottom")
		(1 "F.Mask" user "Board Geometry/Soldermask Top")
		(3 "B.Mask" user "Board Geometry/Soldermask Bottom")
		(17 "Dwgs.User" user "User.Drawings")
		(19 "Cmts.User" user "User.Comments")
		(21 "Eco1.User" user "User.Eco1")
		(23 "Eco2.User" user "User.Eco2")
		(25 "Edge.Cuts" user "Board Geometry/Outline")
		(27 "Margin" user)
		(31 "F.CrtYd" user "Package Geometry/Place Bound Top")
		(29 "B.CrtYd" user "Package Geometry/Place Bound Bottom")
		(35 "F.Fab" user "Ref Des/Assembly Top")
		(33 "B.Fab" user "Ref Des/Assembly Bottom")
	)
	(footprint ""
		(layer "F.Cu")
		(at 84.45246 -84.690204)
		(property "Reference" "Y2"
			(at 1.400048 17.674082 90)
			(unlocked yes)
			(layer "F.SilkS")
			(effects
				(font
					(size 0.7874 0.5842)
					(thickness 0.1524)
				)
				(justify left)
			)
		)
		(property "Value" ""
			(at 0 0 0)
			(layer "F.Fab")
			(effects
				(font
					(size 1.27 1.27)
				)
			)
		)
		(duplicate_pad_numbers_are_jumpers no)
		(fp_line
			(start -1.042162 -2.200402)
			(end -1.042162 2.200402)
			(stroke
				(width 0.1524)
				(type default)
			)
			(layer "F.SilkS")
		)
		(fp_line
			(start -1.042162 2.200402)
			(end -0.0127 2.200402)
			(stroke
				(width 0.1524)
				(type default)
			)
			(layer "F.SilkS")
		)
		(fp_line
			(start -0.1143 -2.200402)
			(end -1.042162 -2.200402)
			(stroke
				(width 0.1524)
				(type default)
			)
			(layer "F.SilkS")
		)
		(fp_line
			(start -0.1143 -2.200402)
			(end 1.042162 -2.200402)
			(stroke
				(width 0.1524)
				(type default)
			)
			(layer "F.SilkS")
		)
		(fp_line
			(start 1.042162 -2.200402)
			(end 1.042162 2.200402)
			(stroke
				(width 0.1524)
				(type default)
			)
			(layer "F.SilkS")
		)
		(fp_line
			(start 1.042162 2.200402)
			(end -0.0381 2.200402)
			(stroke
				(width 0.1524)
				(type default)
			)
			(layer "F.SilkS")
		)
		(fp_poly
			(pts
				(xy -0.8001 -2.100072) (xy -0.8001 -1.8288) (xy -0.9652 -1.8288) (xy -0.9652 -0.6858) (xy -0.8001 -0.6858)
				(xy -0.8001 0.6858) (xy -0.9652 0.6858) (xy -0.9652 1.8288) (xy -0.8001 1.8288) (xy -0.8001 2.100072)
				(xy 0.8001 2.100072) (xy 0.8001 1.8288) (xy 0.9652 1.8288) (xy 0.9652 0.6858) (xy 0.8001 0.6858)
				(xy 0.8001 -0.6858) (xy 0.9652 -0.6858) (xy 0.9652 -1.8288) (xy 0.8001 -1.8288) (xy 0.8001 -2.100072)
			)
			(stroke
				(width 0)
				(type default)
			)
			(fill no)
			(layer "F.CrtYd")
		)
		(fp_line
			(start -0.8001 -2.100072)
			(end -0.8001 2.100072)
			(stroke
				(width 0.1)
				(type default)
			)
			(layer "F.Fab")
		)
		(fp_line
			(start -0.8001 2.100072)
			(end 0.8001 2.100072)
			(stroke
				(width 0.1)
				(type default)
			)
			(layer "F.Fab")
		)
		(fp_line
			(start 0.8001 -2.100072)
			(end -0.8001 -2.100072)
			(stroke
				(width 0.1)
				(type default)
			)
			(layer "F.Fab")
		)
		(fp_line
			(start 0.8001 2.100072)
			(end 0.8001 -2.100072)
			(stroke
				(width 0.1)
				(type default)
			)
			(layer "F.Fab")
		)
		(pad "1" smd rect
			(at 0 -1.249934 270)
			(size 1.016 1.8034)
			(layers "F.Cu" "F.Mask" "F.Paste")
			(net "XTAL_CPU_NODE1_X2PAD")
		)
		(pad "2" smd rect
			(at 0 1.249934 90)
			(size 1.016 1.8034)
			(layers "F.Cu" "F.Mask" "F.Paste")
			(net "XTAL_CPU_NODE1_X1PAD")
		)
	)
	(footprint ""
		(layer "F.Cu")
		(at 125.21057 -26.569416 -90)
		(property "Reference" "R1150"
			(at 5.325618 -0.028448 90)
			(unlocked yes)
			(layer "F.SilkS")
			(effects
				(font
					(size 0.7874 0.5842)
					(thickness 0.1524)
				)
				(justify left)
			)
		)
		(property "Value" ""
			(at 0 0 270)
			(layer "F.Fab")
			(effects
				(font
					(size 1.27 1.27)
				)
			)
		)
		(duplicate_pad_numbers_are_jumpers no)
		(fp_line
			(start -0.7874 0.4064)
			(end -0.7874 -0.4064)
			(stroke
				(width 0.1524)
				(type default)
			)
			(layer "F.SilkS")
		)
		(fp_line
			(start 0.7874 0.4064)
			(end -0.7874 0.4064)
			(stroke
				(width 0.1524)
				(type default)
			)
			(layer "F.SilkS")
		)
		(fp_line
			(start -0.7874 -0.4064)
			(end 0.7874 -0.4064)
			(stroke
				(width 0.1524)
				(type default)
			)
			(layer "F.SilkS")
		)
		(fp_line
			(start 0.7874 -0.4064)
			(end 0.7874 0.4064)
			(stroke
				(width 0.1524)
				(type default)
			)
			(layer "F.SilkS")
		)
		(fp_poly
			(pts
				(xy -0.508 0.2794) (xy -0.508 0.2286) (xy -0.635 0.2286) (xy -0.635 -0.254) (xy -0.5334 -0.254)
				(xy -0.5334 -0.2794) (xy 0.5334 -0.2794) (xy 0.5334 -0.254) (xy 0.635 -0.254) (xy 0.635 0.254) (xy 0.5334 0.254)
				(xy 0.5334 0.2794)
			)
			(stroke
				(width 0)
				(type default)
			)
			(fill no)
			(layer "F.CrtYd")
		)
		(pad "1" smd rect
			(at 0.40005 0 270)
			(size 0.4572 0.508)
			(layers "F.Cu" "F.Mask" "F.Paste")
			(net "P3V3_NODE1")
		)
		(pad "2" smd rect
			(at -0.40005 0 270)
			(size 0.4572 0.508)
			(layers "F.Cu" "F.Mask" "F.Paste")
			(net "SIO_GPIO47")
		)
	)
	(footprint ""
		(layer "F.Cu")
		(at 80.01254 -76.186284 180)
		(property "Reference" "R78"
			(at 0.364744 -16.257524 0)
			(unlocked yes)
			(layer "F.SilkS")
			(effects
				(font
					(size 0.7874 0.5842)
					(thickness 0.1524)
				)
				(justify left)
			)
		)
		(property "Value" ""
			(at 0 0 180)
			(layer "F.Fab")
			(effects
				(font
					(size 1.27 1.27)
				)
			)
		)
		(duplicate_pad_numbers_are_jumpers no)
		(fp_line
			(start 0.7874 0.4064)
			(end -0.7874 0.4064)
			(stroke
				(width 0.1524)
				(type default)
			)
			(layer "F.SilkS")
		)
		(fp_line
			(start 0.7874 -0.4064)
			(end 0.7874 0.4064)
			(stroke
				(width 0.1524)
				(type default)
			)
			(layer "F.SilkS")
		)
		(fp_line
			(start -0.7874 0.4064)
			(end -0.7874 -0.4064)
			(stroke
				(width 0.1524)
				(type default)
			)
			(layer "F.SilkS")
		)
		(fp_line
			(start -0.7874 -0.4064)
			(end 0.7874 -0.4064)
			(stroke
				(width 0.1524)
				(type default)
			)
			(layer "F.SilkS")
		)
		(fp_poly
			(pts
				(xy -0.508 0.2794) (xy -0.508 0.2286) (xy -0.635 0.2286) (xy -0.635 -0.254) (xy -0.5334 -0.254)
				(xy -0.5334 -0.2794) (xy 0.5334 -0.2794) (xy 0.5334 -0.254) (xy 0.635 -0.254) (xy 0.635 0.254) (xy 0.5334 0.254)
				(xy 0.5334 0.2794)
			)
			(stroke
				(width 0)
				(type default)
			)
			(fill no)
			(layer "F.CrtYd")
		)
		(pad "1" smd rect
			(at 0.40005 0 180)
			(size 0.4572 0.508)
			(layers "F.Cu" "F.Mask" "F.Paste")
			(net "XDP_SOC_CPU_NODE1_TCK")
		)
		(pad "2" smd rect
			(at -0.40005 0 180)
			(size 0.4572 0.508)
			(layers "F.Cu" "F.Mask" "F.Paste")
			(net "GND")
		)
	)
	(footprint ""
		(layer "F.Cu")
		(at 33.936178 -175.459898 90)
		(property "Reference" "R1021"
			(at -10.516108 -3.602228 90)
			(unlocked yes)
			(layer "F.SilkS")
			(effects
				(font
					(size 0.7874 0.5842)
					(thickness 0.1524)
				)
				(justify left)
			)
		)
		(property "Value" ""
			(at 0 0 90)
			(layer "F.Fab")
			(effects
				(font
					(size 1.27 1.27)
				)
			)
		)
		(duplicate_pad_numbers_are_jumpers no)
		(fp_line
			(start 0.7874 -0.4064)
			(end 0.7874 0.4064)
			(stroke
				(width 0.1524)
				(type default)
			)
			(layer "F.SilkS")
		)
		(fp_line
			(start -0.7874 -0.4064)
			(end 0.7874 -0.4064)
			(stroke
				(width 0.1524)
				(type default)
			)
			(layer "F.SilkS")
		)
		(fp_line
			(start 0.7874 0.4064)
			(end -0.7874 0.4064)
			(stroke
				(width 0.1524)
				(type default)
			)
			(layer "F.SilkS")
		)
		(fp_line
			(start -0.7874 0.4064)
			(end -0.7874 -0.4064)
			(stroke
				(width 0.1524)
				(type default)
			)
			(layer "F.SilkS")
		)
		(fp_poly
			(pts
				(xy -0.508 0.2794) (xy -0.508 0.2286) (xy -0.635 0.2286) (xy -0.635 -0.254) (xy -0.5334 -0.254)
				(xy -0.5334 -0.2794) (xy 0.5334 -0.2794) (xy 0.5334 -0.254) (xy 0.635 -0.254) (xy 0.635 0.254) (xy 0.5334 0.254)
				(xy 0.5334 0.2794)
			)
			(stroke
				(width 0)
				(type default)
			)
			(fill no)
			(layer "F.CrtYd")
		)
		(pad "1" smd rect
			(at 0.40005 0 90)
			(size 0.4572 0.508)
			(layers "F.Cu" "F.Mask" "F.Paste")
			(net "VR_HSC_NODE1_GATE_R")
		)
		(pad "2" smd rect
			(at -0.40005 0 90)
			(size 0.4572 0.508)
			(layers "F.Cu" "F.Mask" "F.Paste")
			(net "VR_HSC_NODE1_GATE")
		)
	)
	(footprint ""
		(layer "F.Cu")
		(at 119.49176 -175.426624 90)
		(property "Reference" "R797"
			(at -57.011316 32.663638 90)
			(unlocked yes)
			(layer "F.SilkS")
			(effects
				(font
					(size 0.7874 0.5842)
					(thickness 0.1524)
				)
				(justify left)
			)
		)
		(property "Value" ""
			(at 0 0 90)
			(layer "F.Fab")
			(effects
				(font
					(size 1.27 1.27)
				)
			)
		)
		(duplicate_pad_numbers_are_jumpers no)
		(fp_line
			(start 0.7874 -0.4064)
			(end 0.7874 0.4064)
			(stroke
				(width 0.1524)
				(type default)
			)
			(layer "F.SilkS")
		)
		(fp_line
			(start -0.7874 -0.4064)
			(end 0.7874 -0.4064)
			(stroke
				(width 0.1524)
				(type default)
			)
			(layer "F.SilkS")
		)
		(fp_line
			(start 0.7874 0.4064)
			(end -0.7874 0.4064)
			(stroke
				(width 0.1524)
				(type default)
			)
			(layer "F.SilkS")
		)
		(fp_line
			(start -0.7874 0.4064)
			(end -0.7874 -0.4064)
			(stroke
				(width 0.1524)
				(type default)
			)
			(layer "F.SilkS")
		)
		(fp_poly
			(pts
				(xy -0.508 0.2794) (xy -0.508 0.2286) (xy -0.635 0.2286) (xy -0.635 -0.254) (xy -0.5334 -0.254)
				(xy -0.5334 -0.2794) (xy 0.5334 -0.2794) (xy 0.5334 -0.254) (xy 0.635 -0.254) (xy 0.635 0.254) (xy 0.5334 0.254)
				(xy 0.5334 0.2794)
			)
			(stroke
				(width 0)
				(type default)
			)
			(fill no)
			(layer "F.CrtYd")
		)
		(pad "1" smd rect
			(at 0.40005 0 90)
			(size 0.4572 0.508)
			(layers "F.Cu" "F.Mask" "F.Paste")
			(net "N31328108")
		)
		(pad "2" smd rect
			(at -0.40005 0 90)
			(size 0.4572 0.508)
			(layers "F.Cu" "F.Mask" "F.Paste")
			(net "GND")
		)
	)
	(footprint ""
		(layer "F.Cu")
		(at 163.235894 -126.42342 180)
		(property "Reference" "Q28"
			(at -1.400556 1.019556 0)
			(unlocked yes)
			(layer "F.SilkS")
			(effects
				(font
					(size 0.7874 0.5842)
					(thickness 0.1524)
				)
				(justify left)
			)
		)
		(property "Value" ""
			(at 0 0 180)
			(layer "F.Fab")
			(effects
				(font
					(size 1.27 1.27)
				)
			)
		)
		(duplicate_pad_numbers_are_jumpers no)
		(fp_line
			(start 2.584196 2.48412)
			(end -0.5842 2.48412)
			(stroke
				(width 0.1524)
				(type default)
			)
			(layer "F.SilkS")
		)
		(fp_line
			(start 2.584196 -0.5842)
			(end 2.584196 2.48412)
			(stroke
				(width 0.1524)
				(type default)
			)
			(layer "F.SilkS")
		)
		(fp_line
			(start -0.5842 2.48412)
			(end -0.5842 -0.5842)
			(stroke
				(width 0.1524)
				(type default)
			)
			(layer "F.SilkS")
		)
		(fp_line
			(start -0.5842 -0.5842)
			(end 2.584196 -0.5842)
			(stroke
				(width 0.1524)
				(type default)
			)
			(layer "F.SilkS")
		)
		(fp_poly
			(pts
				(xy -0.508 -0.4572) (xy 0.299974 -0.4572) (xy 0.299974 -0.54991) (xy 1.700022 -0.54991) (xy 1.700022 0.49276)
				(xy 2.507996 0.49276) (xy 2.507996 1.40716) (xy 1.700022 1.40716) (xy 1.700022 2.450084) (xy 0.299974 2.450084)
				(xy 0.299974 2.35712) (xy -0.508 2.35712)
			)
			(stroke
				(width 0)
				(type default)
			)
			(fill no)
			(layer "F.CrtYd")
		)
		(fp_line
			(start 1.700022 2.450084)
			(end 0.299974 2.450084)
			(stroke
				(width 0.1)
				(type default)
			)
			(layer "F.Fab")
		)
		(fp_line
			(start 1.700022 -0.54991)
			(end 1.700022 2.450084)
			(stroke
				(width 0.1)
				(type default)
			)
			(layer "F.Fab")
		)
		(fp_line
			(start 0.299974 2.450084)
			(end 0.299974 -0.54991)
			(stroke
				(width 0.1)
				(type default)
			)
			(layer "F.Fab")
		)
		(fp_line
			(start 0.299974 -0.54991)
			(end 1.700022 -0.54991)
			(stroke
				(width 0.1)
				(type default)
			)
			(layer "F.Fab")
		)
		(fp_text user "C"
			(at 3.180842 0.813562 0)
			(unlocked yes)
			(layer "F.SilkS")
			(effects
				(font
					(size 0.635 0.4064)
					(thickness 0.1524)
				)
				(justify left)
			)
		)
		(fp_text user "B"
			(at -0.743712 -0.070866 0)
			(unlocked yes)
			(layer "F.SilkS")
			(effects
				(font
					(size 0.635 0.4064)
					(thickness 0.1524)
				)
				(justify left)
			)
		)
		(fp_text user "E"
			(at -0.771398 1.22809 0)
			(unlocked yes)
			(layer "F.SilkS")
			(effects
				(font
					(size 0.635 0.4064)
					(thickness 0.1524)
				)
				(justify left)
			)
		)
		(fp_text user "C"
			(at 2.8702 0.99187 180)
			(unlocked yes)
			(layer "F.Fab")
			(effects
				(font
					(size 0.7874 0.5842)
					(thickness 0.000001)
				)
				(justify left)
			)
		)
		(fp_text user "B"
			(at -1.5494 0.00127 180)
			(unlocked yes)
			(layer "F.Fab")
			(effects
				(font
					(size 0.7874 0.5842)
					(thickness 0.000001)
				)
				(justify left)
			)
		)
		(fp_text user "E"
			(at -1.5748 1.95707 180)
			(unlocked yes)
			(layer "F.Fab")
			(effects
				(font
					(size 0.7874 0.5842)
					(thickness 0.000001)
				)
				(justify left)
			)
		)
		(pad "B" smd rect
			(at 0 0 270)
			(size 0.8128 0.9144)
			(layers "F.Cu" "F.Mask" "F.Paste")
			(net "FM_CPLD_NODE1_JTAG_POK_R_L")
		)
		(pad "C" smd rect
			(at 1.999996 0.94996 270)
			(size 0.8128 0.9144)
			(layers "F.Cu" "F.Mask" "F.Paste")
			(net "FM_CPU_NODE1_JTAG_POK")
		)
		(pad "E" smd rect
			(at 0 1.89992 270)
			(size 0.8128 0.9144)
			(layers "F.Cu" "F.Mask" "F.Paste")
			(net "GND")
		)
	)
	(footprint ""
		(layer "F.Cu")
		(at 32.014668 -170.403266 180)
		(property "Reference" "R1281"
			(at 3.536188 -7.111746 0)
			(unlocked yes)
			(layer "F.SilkS")
			(effects
				(font
					(size 0.7874 0.5842)
					(thickness 0.1524)
				)
				(justify left)
			)
		)
		(property "Value" ""
			(at 0 0 180)
			(layer "F.Fab")
			(effects
				(font
					(size 1.27 1.27)
				)
			)
		)
		(duplicate_pad_numbers_are_jumpers no)
		(fp_line
			(start 0.7874 0.4064)
			(end -0.7874 0.4064)
			(stroke
				(width 0.1524)
				(type default)
			)
			(layer "F.SilkS")
		)
		(fp_line
			(start 0.7874 -0.4064)
			(end 0.7874 0.4064)
			(stroke
				(width 0.1524)
				(type default)
			)
			(layer "F.SilkS")
		)
		(fp_line
			(start -0.7874 0.4064)
			(end -0.7874 -0.4064)
			(stroke
				(width 0.1524)
				(type default)
			)
			(layer "F.SilkS")
		)
		(fp_line
			(start -0.7874 -0.4064)
			(end 0.7874 -0.4064)
			(stroke
				(width 0.1524)
				(type default)
			)
			(layer "F.SilkS")
		)
		(fp_poly
			(pts
				(xy -0.508 0.2794) (xy -0.508 0.2286) (xy -0.635 0.2286) (xy -0.635 -0.254) (xy -0.5334 -0.254)
				(xy -0.5334 -0.2794) (xy 0.5334 -0.2794) (xy 0.5334 -0.254) (xy 0.635 -0.254) (xy 0.635 0.254) (xy 0.5334 0.254)
				(xy 0.5334 0.2794)
			)
			(stroke
				(width 0)
				(type default)
			)
			(fill no)
			(layer "F.CrtYd")
		)
		(pad "1" smd rect
			(at 0.40005 0 180)
			(size 0.4572 0.508)
			(layers "F.Cu" "F.Mask" "F.Paste")
			(net "CM_PWR_CTL_IN")
		)
		(pad "2" smd rect
			(at -0.40005 0 180)
			(size 0.4572 0.508)
			(layers "F.Cu" "F.Mask" "F.Paste")
			(net "CM_PWR_CTL_IN_R")
		)
	)
	(footprint ""
		(layer "F.Cu")
		(at 93.711522 -129.768092 90)
		(property "Reference" "C811"
			(at -4.228084 -0.049276 90)
			(unlocked yes)
			(layer "F.SilkS")
			(effects
				(font
					(size 0.7874 0.5842)
					(thickness 0.1524)
				)
				(justify left)
			)
		)
		(property "Value" ""
			(at 0 0 90)
			(layer "F.Fab")
			(effects
				(font
					(size 1.27 1.27)
				)
			)
		)
		(duplicate_pad_numbers_are_jumpers no)
		(fp_line
			(start 0.7874 -0.4064)
			(end 0.7874 0.4064)
			(stroke
				(width 0.1524)
				(type default)
			)
			(layer "F.SilkS")
		)
		(fp_line
			(start -0.7874 -0.4064)
			(end 0.7874 -0.4064)
			(stroke
				(width 0.1524)
				(type default)
			)
			(layer "F.SilkS")
		)
		(fp_line
			(start 0 0.381)
			(end 0 -0.381)
			(stroke
				(width 0.1524)
				(type default)
			)
			(layer "F.SilkS")
		)
		(fp_line
			(start 0.7874 0.4064)
			(end -0.7874 0.4064)
			(stroke
				(width 0.1524)
				(type default)
			)
			(layer "F.SilkS")
		)
		(fp_line
			(start -0.7874 0.4064)
			(end -0.7874 -0.4064)
			(stroke
				(width 0.1524)
				(type default)
			)
			(layer "F.SilkS")
		)
		(fp_poly
			(pts
				(xy -0.5334 0.254) (xy -0.635 0.254) (xy -0.635 0.2286) (xy -0.635 -0.254) (xy -0.5334 -0.254) (xy -0.5334 -0.2794)
				(xy 0.5334 -0.2794) (xy 0.5334 -0.254) (xy 0.635 -0.254) (xy 0.635 0.254) (xy 0.5334 0.254) (xy 0.5334 0.2794)
				(xy -0.508 0.2794) (xy -0.5334 0.2794)
			)
			(stroke
				(width 0)
				(type default)
			)
			(fill no)
			(layer "F.CrtYd")
		)
		(pad "1" smd rect
			(at 0.40005 0 90)
			(size 0.4572 0.508)
			(layers "F.Cu" "F.Mask" "F.Paste")
			(net "FM_CPLD_NODE1_P1V05_SUS_EN")
		)
		(pad "2" smd rect
			(at -0.40005 0 90)
			(size 0.4572 0.508)
			(layers "F.Cu" "F.Mask" "F.Paste")
			(net "GND")
		)
	)
	(footprint ""
		(layer "F.Cu")
		(at 116.387372 -137.018522 180)
		(property "Reference" "PR67"
			(at -4.285488 4.322826 0)
			(unlocked yes)
			(layer "F.SilkS")
			(effects
				(font
					(size 0.635 0.4064)
					(thickness 0.1524)
				)
				(justify left)
			)
		)
		(property "Value" ""
			(at 0 0 180)
			(layer "F.Fab")
			(effects
				(font
					(size 1.27 1.27)
				)
			)
		)
		(duplicate_pad_numbers_are_jumpers no)
		(fp_line
			(start 0.7874 0.4064)
			(end -0.7874 0.4064)
			(stroke
				(width 0.1524)
				(type default)
			)
			(layer "F.SilkS")
		)
		(fp_line
			(start 0.7874 -0.4064)
			(end 0.7874 0.4064)
			(stroke
				(width 0.1524)
				(type default)
			)
			(layer "F.SilkS")
		)
		(fp_line
			(start -0.7874 0.4064)
			(end -0.7874 -0.4064)
			(stroke
				(width 0.1524)
				(type default)
			)
			(layer "F.SilkS")
		)
		(fp_line
			(start -0.7874 -0.4064)
			(end 0.7874 -0.4064)
			(stroke
				(width 0.1524)
				(type default)
			)
			(layer "F.SilkS")
		)
		(fp_poly
			(pts
				(xy -0.508 0.2794) (xy -0.508 0.2286) (xy -0.635 0.2286) (xy -0.635 -0.254) (xy -0.5334 -0.254)
				(xy -0.5334 -0.2794) (xy 0.5334 -0.2794) (xy 0.5334 -0.254) (xy 0.635 -0.254) (xy 0.635 0.254) (xy 0.5334 0.254)
				(xy 0.5334 0.2794)
			)
			(stroke
				(width 0)
				(type default)
			)
			(fill no)
			(layer "F.CrtYd")
		)
		(pad "1" smd rect
			(at 0.40005 0 180)
			(size 0.4572 0.508)
			(layers "F.Cu" "F.Mask" "F.Paste")
			(net "VR_PVCCP_NODE1_FB")
		)
		(pad "2" smd rect
			(at -0.40005 0 180)
			(size 0.4572 0.508)
			(layers "F.Cu" "F.Mask" "F.Paste")
			(net "VR_PVCCP_NODE1_FB_RC")
		)
	)
)
